(kicad_sch
	(version 20250114)
	(generator "eeschema")
	(generator_version "9.0")
	(paper "A3")
	(title_block
		(title "SO-DIMM DDR5 Tester")
		(date "2025-11-26")
		(rev "1.3.0")
		(company "Antmicro Ltd.")
		(comment 1 "www.antmicro.com")
		(comment 2 "Antmicro Ltd")
	)
	(bus_alias "DDR5"
		(members "DQ[0..31]" "CA[0..12]" "~{DM[0..3]}" "CB[0..3]" "DQS0_P" "DQS0_N"
			"DQS1_P" "DQS1_N" "DQS2_P" "DQS2_N" "DQS3_P" "DQS3_N" "DQS4_P" "DQS4_N"
			"CK0_P" "CK0_N" "CK1_P" "CK1_N" "~{CS0}" "~{CS1}" "~{ALERT}" "~{RESET}"
			"PWR_GOOD" "PWR_EN"
		)
	)
	(bus_alias "HyperBus"
		(members "~{CS}" "CK_P" "CK_N" "RWDS" "DQ[0..7]" "~{RESET}")
	)
	(bus_alias "I^{2}C"
		(members "SDA" "SCL")
	)
	(bus_alias "JTAG"
		(members "TDO" "TMS" "TCK" "RST" "TDI")
	)
	(bus_alias "PCIe_x4"
		(members "TXD0_P" "TXD0_N" "TXD1_P" "TXD1_N" "TXD2_P" "TXD2_N" "TXD3_P"
			"TXD3_N" "RXD0_P" "RXD0_N" "RXD1_P" "RXD1_N" "RXD2_P" "RXD2_N" "RXD3_P"
			"RXD3_N" "CLK_P" "CLK_N"
		)
	)
	(bus_alias "QSPI"
		(members "IO[0..3]" "~{CS}" "SCK")
	)
	(bus_alias "RGMII"
		(members "~{RESET}" "~{INT}" "MDC" "MDIO" "TX_CTL" "TXD[0..3]" "TXC" "RX_CTL"
			"RXD[0..3]" "RXC" "REF_CLK"
		)
	)
	(bus_alias "SDIO"
		(members "DAT[0..3]" "CMD" "CLK" "CD")
	)
	(bus_alias "TMDS"
		(members "D0_P" "D0_N" "D1_P" "D1_N" "D2_P" "D2_N" "CLK_P" "CLK_N")
	)
	(bus_alias "UART"
		(members "TX" "RX")
	)
	(bus_alias "USB"
		(members "D+")
	)
	(text "FPGA\nKintex 7\nXC7K160T"
		(exclude_from_sim no)
		(at 201.295 141.605 0)
		(effects
			(font
				(size 2.54 2.54)
			)
			(justify left bottom)
		)
	)
	(text "JTAG"
		(exclude_from_sim no)
		(at 178.435 129.54 0)
		(effects
			(font
				(size 1.27 1.27)
			)
			(justify left bottom)
		)
	)
	(text "User LEDs"
		(exclude_from_sim no)
		(at 173.355 163.83 0)
		(effects
			(font
				(size 1.27 1.27)
			)
			(justify left bottom)
		)
	)
	(text "Mechanical"
		(exclude_from_sim no)
		(at 254 259.715 0)
		(effects
			(font
				(size 1.27 1.27)
				(thickness 0.254)
				(bold yes)
			)
			(justify left bottom)
		)
	)
	(text "Status LEDs"
		(exclude_from_sim no)
		(at 171.45 132.08 0)
		(effects
			(font
				(size 1.27 1.27)
			)
			(justify left bottom)
		)
	)
	(text "SO-DIMM DDR5 Tester"
		(exclude_from_sim no)
		(at 172.085 35.56 0)
		(effects
			(font
				(size 3.9878 3.9878)
				(thickness 0.7976)
				(bold yes)
			)
			(justify left bottom)
		)
	)
	(text "100MHz Clock"
		(exclude_from_sim no)
		(at 169.545 195.58 0)
		(effects
			(font
				(size 1.27 1.27)
			)
			(justify left bottom)
		)
	)
	(junction
		(at 276.225 76.2)
		(diameter 0)
		(color 0 0 0 0)
	)
	(junction
		(at 142.875 118.745)
		(diameter 0)
		(color 0 0 0 0)
	)
	(bus
		(pts
			(xy 127 153.035) (xy 146.05 153.035)
		)
		(stroke
			(width 0)
			(type default)
		)
	)
	(bus
		(pts
			(xy 127 212.09) (xy 137.795 212.09)
		)
		(stroke
			(width 0)
			(type default)
		)
	)
	(bus
		(pts
			(xy 140.97 182.88) (xy 140.97 214.63)
		)
		(stroke
			(width 0)
			(type default)
		)
	)
	(bus
		(pts
			(xy 146.05 182.88) (xy 140.97 182.88)
		)
		(stroke
			(width 0)
			(type default)
		)
	)
	(bus
		(pts
			(xy 146.05 84.455) (xy 142.875 84.455)
		)
		(stroke
			(width 0)
			(type default)
		)
	)
	(bus
		(pts
			(xy 273.05 89.535) (xy 281.94 89.535)
		)
		(stroke
			(width 0)
			(type default)
		)
	)
	(bus
		(pts
			(xy 146.05 130.81) (xy 129.54 130.81)
		)
		(stroke
			(width 0)
			(type default)
		)
	)
	(bus
		(pts
			(xy 82.55 234.95) (xy 336.55 234.95)
		)
		(stroke
			(width 0)
			(type default)
		)
	)
	(bus
		(pts
			(xy 129.54 180.34) (xy 129.54 158.115)
		)
		(stroke
			(width 0)
			(type default)
		)
	)
	(bus
		(pts
			(xy 187.96 147.955) (xy 187.96 107.95)
		)
		(stroke
			(width 0)
			(type default)
		)
	)
	(bus
		(pts
			(xy 129.54 89.535) (xy 129.54 116.205)
		)
		(stroke
			(width 0)
			(type default)
		)
	)
	(bus
		(pts
			(xy 278.765 86.995) (xy 273.05 86.995)
		)
		(stroke
			(width 0)
			(type default)
		)
	)
	(bus
		(pts
			(xy 82.55 53.34) (xy 88.9 53.34)
		)
		(stroke
			(width 0)
			(type default)
		)
	)
	(bus
		(pts
			(xy 129.54 116.205) (xy 127 116.205)
		)
		(stroke
			(width 0)
			(type default)
		)
	)
	(bus
		(pts
			(xy 88.9 180.34) (xy 82.55 180.34)
		)
		(stroke
			(width 0)
			(type default)
		)
	)
	(bus
		(pts
			(xy 273.05 65.405) (xy 278.765 65.405)
		)
		(stroke
			(width 0)
			(type default)
		)
	)
	(bus
		(pts
			(xy 127 185.42) (xy 134.62 185.42)
		)
		(stroke
			(width 0)
			(type default)
		)
	)
	(bus
		(pts
			(xy 146.05 89.535) (xy 129.54 89.535)
		)
		(stroke
			(width 0)
			(type default)
		)
	)
	(bus
		(pts
			(xy 134.62 160.655) (xy 146.05 160.655)
		)
		(stroke
			(width 0)
			(type default)
		)
	)
	(bus
		(pts
			(xy 276.225 84.455) (xy 276.225 76.2)
		)
		(stroke
			(width 0)
			(type default)
		)
	)
	(polyline
		(pts
			(xy 144.78 200.66) (xy 274.32 200.66)
		)
		(stroke
			(width 0)
			(type dash)
		)
	)
	(bus
		(pts
			(xy 276.225 67.945) (xy 273.05 67.945)
		)
		(stroke
			(width 0)
			(type default)
		)
	)
	(bus
		(pts
			(xy 285.75 212.09) (xy 273.05 212.09)
		)
		(stroke
			(width 0)
			(type default)
		)
	)
	(bus
		(pts
			(xy 142.875 76.2) (xy 276.225 76.2)
		)
		(stroke
			(width 0)
			(type default)
		)
	)
	(bus
		(pts
			(xy 276.225 76.2) (xy 276.225 67.945)
		)
		(stroke
			(width 0)
			(type default)
		)
	)
	(bus
		(pts
			(xy 142.875 107.95) (xy 142.875 118.745)
		)
		(stroke
			(width 0)
			(type default)
		)
	)
	(polyline
		(pts
			(xy 144.78 79.375) (xy 274.32 79.375)
		)
		(stroke
			(width 0)
			(type dash)
		)
	)
	(polyline
		(pts
			(xy 274.32 200.66) (xy 274.32 79.375)
		)
		(stroke
			(width 0)
			(type dash)
		)
	)
	(bus
		(pts
			(xy 330.2 226.06) (xy 336.55 226.06)
		)
		(stroke
			(width 0)
			(type default)
		)
	)
	(bus
		(pts
			(xy 142.875 84.455) (xy 142.875 76.2)
		)
		(stroke
			(width 0)
			(type default)
		)
	)
	(bus
		(pts
			(xy 146.05 158.115) (xy 132.08 158.115)
		)
		(stroke
			(width 0)
			(type default)
		)
	)
	(bus
		(pts
			(xy 129.54 130.81) (xy 129.54 147.955)
		)
		(stroke
			(width 0)
			(type default)
		)
	)
	(bus
		(pts
			(xy 127 180.34) (xy 129.54 180.34)
		)
		(stroke
			(width 0)
			(type default)
		)
	)
	(bus
		(pts
			(xy 142.875 118.745) (xy 146.05 118.745)
		)
		(stroke
			(width 0)
			(type default)
		)
	)
	(bus
		(pts
			(xy 129.54 147.955) (xy 127 147.955)
		)
		(stroke
			(width 0)
			(type default)
		)
	)
	(bus
		(pts
			(xy 132.08 182.88) (xy 132.08 158.115)
		)
		(stroke
			(width 0)
			(type default)
		)
	)
	(bus
		(pts
			(xy 127 158.115) (xy 129.54 158.115)
		)
		(stroke
			(width 0)
			(type default)
		)
	)
	(bus
		(pts
			(xy 273.05 194.31) (xy 285.75 194.31)
		)
		(stroke
			(width 0)
			(type default)
		)
	)
	(bus
		(pts
			(xy 140.97 214.63) (xy 127 214.63)
		)
		(stroke
			(width 0)
			(type default)
		)
	)
	(bus
		(pts
			(xy 278.765 65.405) (xy 278.765 86.995)
		)
		(stroke
			(width 0)
			(type default)
		)
	)
	(bus
		(pts
			(xy 127 86.995) (xy 146.05 86.995)
		)
		(stroke
			(width 0)
			(type default)
		)
	)
	(bus
		(pts
			(xy 276.225 84.455) (xy 273.05 84.455)
		)
		(stroke
			(width 0)
			(type default)
		)
	)
	(bus
		(pts
			(xy 127 155.575) (xy 146.05 155.575)
		)
		(stroke
			(width 0)
			(type default)
		)
	)
	(bus
		(pts
			(xy 137.795 212.09) (xy 137.795 180.34)
		)
		(stroke
			(width 0)
			(type default)
		)
	)
	(bus
		(pts
			(xy 82.55 180.34) (xy 82.55 53.34)
		)
		(stroke
			(width 0)
			(type default)
		)
	)
	(bus
		(pts
			(xy 281.94 62.865) (xy 273.05 62.865)
		)
		(stroke
			(width 0)
			(type default)
		)
	)
	(bus
		(pts
			(xy 285.75 194.31) (xy 285.75 212.09)
		)
		(stroke
			(width 0)
			(type default)
		)
	)
	(bus
		(pts
			(xy 127 118.745) (xy 142.875 118.745)
		)
		(stroke
			(width 0)
			(type default)
		)
	)
	(bus
		(pts
			(xy 187.96 107.95) (xy 142.875 107.95)
		)
		(stroke
			(width 0)
			(type default)
		)
	)
	(bus
		(pts
			(xy 127 182.88) (xy 132.08 182.88)
		)
		(stroke
			(width 0)
			(type default)
		)
	)
	(bus
		(pts
			(xy 336.55 226.06) (xy 336.55 234.95)
		)
		(stroke
			(width 0)
			(type default)
		)
	)
	(bus
		(pts
			(xy 127 150.495) (xy 146.05 150.495)
		)
		(stroke
			(width 0)
			(type default)
		)
	)
	(bus
		(pts
			(xy 184.15 147.955) (xy 187.96 147.955)
		)
		(stroke
			(width 0)
			(type default)
		)
	)
	(bus
		(pts
			(xy 82.55 194.31) (xy 82.55 234.95)
		)
		(stroke
			(width 0)
			(type default)
		)
	)
	(bus
		(pts
			(xy 137.795 180.34) (xy 146.05 180.34)
		)
		(stroke
			(width 0)
			(type default)
		)
	)
	(polyline
		(pts
			(xy 144.78 79.375) (xy 144.78 200.66)
		)
		(stroke
			(width 0)
			(type dash)
		)
	)
	(bus
		(pts
			(xy 88.9 194.31) (xy 82.55 194.31)
		)
		(stroke
			(width 0)
			(type default)
		)
	)
	(bus
		(pts
			(xy 134.62 185.42) (xy 134.62 160.655)
		)
		(stroke
			(width 0)
			(type default)
		)
	)
	(bus
		(pts
			(xy 281.94 89.535) (xy 281.94 62.865)
		)
		(stroke
			(width 0)
			(type default)
		)
	)
	(symbol
		(lib_id "antmicroMechanicalParts:Heatsink_960-27-12-D-AB-0")
		(at 254 262.255 0)
		(unit 1)
		(exclude_from_sim no)
		(in_bom no)
		(on_board yes)
		(dnp yes)
		(fields_autoplaced yes)
		(property "Reference" "H1"
			(at 260.35 263.6469 0)
			(effects
				(font
					(size 1.27 1.27)
					(thickness 0.15)
				)
				(justify left)
			)
		)
		(property "Value" "Heatsink_960-27-12-D-AB-0"
			(at 260.35 266.1706 0)
			(effects
				(font
					(size 1.27 1.27)
					(thickness 0.15)
				)
				(justify left)
				(hide yes)
			)
		)
		(property "Footprint" "antmicro-footprints:Heatsink_960-27-12-D-AB-0"
			(at 271.78 269.875 0)
			(effects
				(font
					(size 1.27 1.27)
					(thickness 0.15)
				)
				(justify left bottom)
				(hide yes)
			)
		)
		(property "Datasheet" "https://media.digikey.com/pdf/Data%20Sheets/Wakefield%20Thermal%20PDFs/960_Series.pdf"
			(at 271.78 272.415 0)
			(effects
				(font
					(size 1.27 1.27)
					(thickness 0.15)
				)
				(justify left bottom)
				(hide yes)
			)
		)
		(property "Description" ""
			(at 254 262.255 0)
			(effects
				(font
					(size 1.27 1.27)
				)
			)
		)
		(property "MPN" "960-27-12-D-AB-0"
			(at 260.35 266.1706 0)
			(effects
				(font
					(size 1.27 1.27)
					(thickness 0.15)
				)
				(justify left)
			)
		)
		(property "Manufacturer" "Wakefield-Vette"
			(at 271.78 277.495 0)
			(effects
				(font
					(size 1.27 1.27)
					(thickness 0.15)
				)
				(justify left bottom)
				(hide yes)
			)
		)
		(property "Author" "Antmicro"
			(at 271.78 280.035 0)
			(effects
				(font
					(size 1.27 1.27)
					(thickness 0.15)
				)
				(justify left bottom)
				(hide yes)
			)
		)
		(property "License" "Apache-2.0"
			(at 271.78 282.575 0)
			(effects
				(font
					(size 1.27 1.27)
					(thickness 0.15)
				)
				(justify left bottom)
				(hide yes)
			)
		)
		(instances
			(project "sodimm-ddr5-tester"
				(path ""
					(reference "H1")
					(unit 1)
				)
			)
		)
	)
	(symbol
		(lib_id "antmicroMechanicalParts:Lightpipe_Mentor_1296.2013")
		(at 259.08 276.86 0)
		(unit 1)
		(exclude_from_sim no)
		(in_bom yes)
		(on_board yes)
		(dnp no)
		(fields_autoplaced yes)
		(property "Reference" "H2"
			(at 264.922 275.3944 0)
			(effects
				(font
					(size 1.27 1.27)
					(thickness 0.15)
				)
				(justify left)
			)
		)
		(property "Value" "Lightpipe_Mentor_1296.2013"
			(at 264.922 277.9181 0)
			(effects
				(font
					(size 1.27 1.27)
					(thickness 0.15)
				)
				(justify left)
			)
		)
		(property "Footprint" "antmicro-footprints:Mech_Lightpipe_Mentor_1296.2013"
			(at 279.4 284.48 0)
			(effects
				(font
					(size 1.27 1.27)
					(thickness 0.15)
				)
				(justify left bottom)
				(hide yes)
			)
		)
		(property "Datasheet" "https://docs.rs-online.com/e47b/0900766b813f6efb.pdf"
			(at 279.4 287.02 0)
			(effects
				(font
					(size 1.27 1.27)
					(thickness 0.15)
				)
				(justify left bottom)
				(hide yes)
			)
		)
		(property "Description" ""
			(at 259.08 276.86 0)
			(effects
				(font
					(size 1.27 1.27)
				)
			)
		)
		(property "Manufacturer" "Mentor Worldwide"
			(at 279.4 289.56 0)
			(effects
				(font
					(size 1.27 1.27)
					(thickness 0.15)
				)
				(justify left bottom)
				(hide yes)
			)
		)
		(property "MPN" "1296.2013"
			(at 279.4 292.1 0)
			(effects
				(font
					(size 1.27 1.27)
					(thickness 0.15)
				)
				(justify left bottom)
				(hide yes)
			)
		)
		(property "Author" "Antmicro"
			(at 279.4 294.64 0)
			(effects
				(font
					(size 1.27 1.27)
					(thickness 0.15)
				)
				(justify left bottom)
				(hide yes)
			)
		)
		(property "License" "Apache-2.0"
			(at 279.4 297.18 0)
			(effects
				(font
					(size 1.27 1.27)
					(thickness 0.15)
				)
				(justify left bottom)
				(hide yes)
			)
		)
		(instances
			(project "sodimm-ddr5-tester"
				(path ""
					(reference "H2")
					(unit 1)
				)
			)
		)
	)
	(sheet
		(at 88.9 82.55)
		(size 38.1 19.05)
		(exclude_from_sim no)
		(in_bom yes)
		(on_board yes)
		(dnp no)
		(fields_autoplaced yes)
		(stroke
			(width 0)
			(type solid)
		)
		(fill
			(color 0 0 0 0.0000)
		)
		(property "Sheetname" "Ethernet"
			(at 88.9 81.8384 0)
			(effects
				(font
					(size 1.27 1.27)
				)
				(justify left bottom)
			)
		)
		(property "Sheetfile" "ethernet.kicad_sch"
			(at 88.9 102.1846 0)
			(effects
				(font
					(size 1.27 1.27)
				)
				(justify left top)
			)
		)
		(pin "ETH{RGMII}" bidirectional
			(at 127 86.995 0)
			(effects
				(font
					(size 1.27 1.27)
				)
				(justify right)
			)
		)
		(instances
			(project "sodimm-ddr5-tester"
				(path ""
					(page "8")
				)
			)
		)
	)
	(sheet
		(at 146.05 114.3)
		(size 38.1 19.05)
		(exclude_from_sim no)
		(in_bom yes)
		(on_board yes)
		(dnp no)
		(fields_autoplaced yes)
		(stroke
			(width 0)
			(type solid)
		)
		(fill
			(color 0 0 0 0.0000)
		)
		(property "Sheetname" "FPGA Config"
			(at 146.05 113.5884 0)
			(effects
				(font
					(size 1.27 1.27)
				)
				(justify left bottom)
			)
		)
		(property "Sheetfile" "fpga-config.kicad_sch"
			(at 146.05 133.9346 0)
			(effects
				(font
					(size 1.27 1.27)
				)
				(justify left top)
			)
		)
		(pin "JTAG{JTAG}" bidirectional
			(at 146.05 130.81 180)
			(effects
				(font
					(size 1.27 1.27)
				)
				(justify left)
			)
		)
		(pin "FLASH{QSPI}" bidirectional
			(at 146.05 118.745 180)
			(effects
				(font
					(size 1.27 1.27)
				)
				(justify left)
			)
		)
		(instances
			(project "sodimm-ddr5-tester"
				(path ""
					(page "3")
				)
			)
		)
	)
	(sheet
		(at 88.9 114.3)
		(size 38.1 19.05)
		(exclude_from_sim no)
		(in_bom yes)
		(on_board yes)
		(dnp no)
		(fields_autoplaced yes)
		(stroke
			(width 0)
			(type solid)
		)
		(fill
			(color 0 0 0 0.0000)
		)
		(property "Sheetname" "HyperRAM + QSPI Flash"
			(at 88.9 113.5884 0)
			(effects
				(font
					(size 1.27 1.27)
				)
				(justify left bottom)
			)
		)
		(property "Sheetfile" "hyperram-flash.kicad_sch"
			(at 88.9 133.9346 0)
			(effects
				(font
					(size 1.27 1.27)
				)
				(justify left top)
			)
		)
		(pin "HyperRAM{HyperBus}" bidirectional
			(at 127 116.205 0)
			(effects
				(font
					(size 1.27 1.27)
				)
				(justify right)
			)
		)
		(pin "FLASH{QSPI}" bidirectional
			(at 127 118.745 0)
			(effects
				(font
					(size 1.27 1.27)
				)
				(justify right)
			)
		)
		(instances
			(project "sodimm-ddr5-tester"
				(path ""
					(page "2")
				)
			)
		)
	)
	(sheet
		(at 234.95 114.3)
		(size 38.1 19.05)
		(exclude_from_sim no)
		(in_bom yes)
		(on_board yes)
		(dnp no)
		(fields_autoplaced yes)
		(stroke
			(width 0)
			(type solid)
		)
		(fill
			(color 0 0 0 0.0000)
		)
		(property "Sheetname" "FPGA power"
			(at 234.95 113.5884 0)
			(effects
				(font
					(size 1.27 1.27)
				)
				(justify left bottom)
			)
		)
		(property "Sheetfile" "fpga-power.kicad_sch"
			(at 234.95 133.9346 0)
			(effects
				(font
					(size 1.27 1.27)
				)
				(justify left top)
			)
		)
		(instances
			(project "sodimm-ddr5-tester"
				(path ""
					(page "5")
				)
			)
		)
	)
	(sheet
		(at 88.9 146.05)
		(size 38.1 19.05)
		(exclude_from_sim no)
		(in_bom yes)
		(on_board yes)
		(dnp no)
		(fields_autoplaced yes)
		(stroke
			(width 0)
			(type solid)
		)
		(fill
			(color 0 0 0 0.0000)
		)
		(property "Sheetname" "Debug FTDI"
			(at 88.9 145.3384 0)
			(effects
				(font
					(size 1.27 1.27)
				)
				(justify left bottom)
			)
		)
		(property "Sheetfile" "debug-ftdi.kicad_sch"
			(at 88.9 165.6846 0)
			(effects
				(font
					(size 1.27 1.27)
				)
				(justify left top)
			)
		)
		(pin "UART1{UART}" bidirectional
			(at 127 155.575 0)
			(effects
				(font
					(size 1.27 1.27)
				)
				(justify right)
			)
		)
		(pin "AUX{JTAG}" bidirectional
			(at 127 150.495 0)
			(effects
				(font
					(size 1.27 1.27)
				)
				(justify right)
			)
		)
		(pin "UART0{UART}" bidirectional
			(at 127 153.035 0)
			(effects
				(font
					(size 1.27 1.27)
				)
				(justify right)
			)
		)
		(pin "JTAG{JTAG}" bidirectional
			(at 127 147.955 0)
			(effects
				(font
					(size 1.27 1.27)
				)
				(justify right)
			)
		)
		(pin "FTDI{I^{2}C}" bidirectional
			(at 127 158.115 0)
			(effects
				(font
					(size 1.27 1.27)
				)
				(justify right)
			)
		)
		(instances
			(project "sodimm-ddr5-tester"
				(path ""
					(page "6")
				)
			)
		)
	)
	(sheet
		(at 292.1 50.8)
		(size 38.1 177.8)
		(exclude_from_sim no)
		(in_bom yes)
		(on_board yes)
		(dnp no)
		(fields_autoplaced yes)
		(stroke
			(width 0)
			(type solid)
		)
		(fill
			(color 0 0 0 0.0000)
		)
		(property "Sheetname" "Supply"
			(at 292.1 50.0884 0)
			(effects
				(font
					(size 1.27 1.27)
				)
				(justify left bottom)
			)
		)
		(property "Sheetfile" "supply.kicad_sch"
			(at 292.1 229.1846 0)
			(effects
				(font
					(size 1.27 1.27)
				)
				(justify left top)
			)
		)
		(pin "PWR{I^{2}C}" bidirectional
			(at 330.2 226.06 0)
			(effects
				(font
					(size 1.27 1.27)
				)
				(justify right)
			)
		)
		(instances
			(project "sodimm-ddr5-tester"
				(path ""
					(page "10")
				)
			)
		)
	)
	(sheet
		(at 88.9 50.8)
		(size 184.15 19.05)
		(exclude_from_sim no)
		(in_bom yes)
		(on_board yes)
		(dnp no)
		(fields_autoplaced yes)
		(stroke
			(width 0)
			(type solid)
		)
		(fill
			(color 0 0 0 0.0000)
		)
		(property "Sheetname" "DDR5 SODIMM"
			(at 88.9 50.0884 0)
			(effects
				(font
					(size 1.27 1.27)
				)
				(justify left bottom)
			)
		)
		(property "Sheetfile" "ddr5-sodimm.kicad_sch"
			(at 88.9 70.4346 0)
			(effects
				(font
					(size 1.27 1.27)
				)
				(justify left top)
			)
		)
		(pin "B{DDR5}" input
			(at 273.05 65.405 0)
			(effects
				(font
					(size 1.27 1.27)
				)
				(justify right)
			)
		)
		(pin "A{DDR5}" input
			(at 273.05 62.865 0)
			(effects
				(font
					(size 1.27 1.27)
				)
				(justify right)
			)
		)
		(pin "Control{DDR5}" input
			(at 273.05 67.945 0)
			(effects
				(font
					(size 1.27 1.27)
				)
				(justify right)
			)
		)
		(pin "DDR{I^{2}C}" bidirectional
			(at 88.9 53.34 180)
			(effects
				(font
					(size 1.27 1.27)
				)
				(justify left)
			)
		)
		(instances
			(project "sodimm-ddr5-tester"
				(path ""
					(page "4")
				)
			)
		)
	)
	(sheet
		(at 190.5 82.55)
		(size 82.55 19.05)
		(exclude_from_sim no)
		(in_bom yes)
		(on_board yes)
		(dnp no)
		(fields_autoplaced yes)
		(stroke
			(width 0)
			(type solid)
		)
		(fill
			(color 0 0 0 0.0000)
		)
		(property "Sheetname" "FPGA banks HP"
			(at 190.5 81.8384 0)
			(effects
				(font
					(size 1.27 1.27)
				)
				(justify left bottom)
			)
		)
		(property "Sheetfile" "fpga-banks-32-34.kicad_sch"
			(at 190.5 102.1846 0)
			(effects
				(font
					(size 1.27 1.27)
				)
				(justify left top)
			)
		)
		(pin "A{DDR5}" input
			(at 273.05 89.535 0)
			(effects
				(font
					(size 1.27 1.27)
				)
				(justify right)
			)
		)
		(pin "B{DDR5}" input
			(at 273.05 86.995 0)
			(effects
				(font
					(size 1.27 1.27)
				)
				(justify right)
			)
		)
		(pin "Control{DDR5}" input
			(at 273.05 84.455 0)
			(effects
				(font
					(size 1.27 1.27)
				)
				(justify right)
			)
		)
		(instances
			(project "sodimm-ddr5-tester"
				(path ""
					(page "9")
				)
			)
		)
	)
	(sheet
		(at 146.05 146.05)
		(size 38.1 19.05)
		(exclude_from_sim no)
		(in_bom yes)
		(on_board yes)
		(dnp no)
		(fields_autoplaced yes)
		(stroke
			(width 0.1524)
			(type solid)
		)
		(fill
			(color 0 0 0 0.0000)
		)
		(property "Sheetname" "FPGA bank 14"
			(at 146.05 145.3384 0)
			(effects
				(font
					(size 1.27 1.27)
				)
				(justify left bottom)
			)
		)
		(property "Sheetfile" "fpga-bank-14.kicad_sch"
			(at 146.05 165.6846 0)
			(effects
				(font
					(size 1.27 1.27)
				)
				(justify left top)
			)
		)
		(pin "FLASH{QSPI}" bidirectional
			(at 184.15 147.955 0)
			(effects
				(font
					(size 1.27 1.27)
				)
				(justify right)
			)
		)
		(pin "UART0{UART}" bidirectional
			(at 146.05 153.035 180)
			(effects
				(font
					(size 1.27 1.27)
				)
				(justify left)
			)
		)
		(pin "AUX{JTAG}" bidirectional
			(at 146.05 150.495 180)
			(effects
				(font
					(size 1.27 1.27)
				)
				(justify left)
			)
		)
		(pin "UART1{UART}" bidirectional
			(at 146.05 155.575 180)
			(effects
				(font
					(size 1.27 1.27)
				)
				(justify left)
			)
		)
		(pin "FPGA_PWR{I^{2}C}" bidirectional
			(at 146.05 160.655 180)
			(effects
				(font
					(size 1.27 1.27)
				)
				(justify left)
			)
		)
		(pin "FPGA_DDR{I^{2}C}" bidirectional
			(at 146.05 158.115 180)
			(effects
				(font
					(size 1.27 1.27)
				)
				(justify left)
			)
		)
		(instances
			(project "sodimm-ddr5-tester"
				(path ""
					(page "15")
				)
			)
		)
	)
	(sheet
		(at 146.05 82.55)
		(size 38.1 19.05)
		(exclude_from_sim no)
		(in_bom yes)
		(on_board yes)
		(dnp no)
		(fields_autoplaced yes)
		(stroke
			(width 0.1524)
			(type solid)
		)
		(fill
			(color 0 0 0 0.0000)
		)
		(property "Sheetname" "FPGA bank 12"
			(at 146.05 81.8384 0)
			(effects
				(font
					(size 1.27 1.27)
				)
				(justify left bottom)
			)
		)
		(property "Sheetfile" "fpga-bank-12.kicad_sch"
			(at 146.05 102.1846 0)
			(effects
				(font
					(size 1.27 1.27)
				)
				(justify left top)
			)
		)
		(pin "ETH{RGMII}" bidirectional
			(at 146.05 86.995 180)
			(effects
				(font
					(size 1.27 1.27)
				)
				(justify left)
			)
		)
		(pin "HyperRAM{HyperBus}" bidirectional
			(at 146.05 89.535 180)
			(effects
				(font
					(size 1.27 1.27)
				)
				(justify left)
			)
		)
		(pin "Control{DDR5}" input
			(at 146.05 84.455 180)
			(effects
				(font
					(size 1.27 1.27)
				)
				(justify left)
			)
		)
		(instances
			(project "sodimm-ddr5-tester"
				(path ""
					(page "13")
				)
			)
		)
	)
	(sheet
		(at 88.9 177.8)
		(size 38.1 19.05)
		(exclude_from_sim no)
		(in_bom yes)
		(on_board yes)
		(dnp no)
		(fields_autoplaced yes)
		(stroke
			(width 0.1524)
			(type solid)
		)
		(fill
			(color 0 0 0 0.0000)
		)
		(property "Sheetname" "I^{2}C"
			(at 88.9 177.0884 0)
			(effects
				(font
					(size 1.27 1.27)
				)
				(justify left bottom)
			)
		)
		(property "Sheetfile" "i2c.kicad_sch"
			(at 88.9 197.4346 0)
			(effects
				(font
					(size 1.27 1.27)
				)
				(justify left top)
			)
		)
		(pin "FPGA_DDR{I^{2}C}" bidirectional
			(at 127 182.88 0)
			(effects
				(font
					(size 1.27 1.27)
				)
				(justify right)
			)
		)
		(pin "FPGA_PWR{I^{2}C}" bidirectional
			(at 127 185.42 0)
			(effects
				(font
					(size 1.27 1.27)
				)
				(justify right)
			)
		)
		(pin "FTDI{I^{2}C}" bidirectional
			(at 127 180.34 0)
			(effects
				(font
					(size 1.27 1.27)
				)
				(justify right)
			)
		)
		(pin "PWR{I^{2}C}" bidirectional
			(at 88.9 194.31 180)
			(effects
				(font
					(size 1.27 1.27)
				)
				(justify left)
			)
		)
		(pin "DDR{I^{2}C}" bidirectional
			(at 88.9 180.34 180)
			(effects
				(font
					(size 1.27 1.27)
				)
				(justify left)
			)
		)
		(instances
			(project "sodimm-ddr5-tester"
				(path ""
					(page "17")
				)
			)
		)
	)
	(sheet
		(at 88.9 209.55)
		(size 38.1 19.05)
		(exclude_from_sim no)
		(in_bom yes)
		(on_board yes)
		(dnp no)
		(fields_autoplaced yes)
		(stroke
			(width 0.1524)
			(type solid)
		)
		(fill
			(color 0 0 0 0.0000)
		)
		(property "Sheetname" "HDMI + SD Card"
			(at 88.9 208.8384 0)
			(effects
				(font
					(size 1.27 1.27)
				)
				(justify left bottom)
			)
		)
		(property "Sheetfile" "hdmi-sd-card.kicad_sch"
			(at 88.9 229.1846 0)
			(effects
				(font
					(size 1.27 1.27)
				)
				(justify left top)
			)
		)
		(pin "HDMI{TMDS}" bidirectional
			(at 127 214.63 0)
			(effects
				(font
					(size 1.27 1.27)
				)
				(justify right)
			)
		)
		(pin "SD{SDIO}" bidirectional
			(at 127 212.09 0)
			(effects
				(font
					(size 1.27 1.27)
				)
				(justify right)
			)
		)
		(instances
			(project "sodimm-ddr5-tester"
				(path ""
					(page "17")
				)
			)
		)
	)
	(sheet
		(at 146.05 177.8)
		(size 38.1 19.05)
		(exclude_from_sim no)
		(in_bom yes)
		(on_board yes)
		(dnp no)
		(fields_autoplaced yes)
		(stroke
			(width 0.1524)
			(type solid)
		)
		(fill
			(color 0 0 0 0.0000)
		)
		(property "Sheetname" "FPGA bank 16"
			(at 146.05 177.0884 0)
			(effects
				(font
					(size 1.27 1.27)
				)
				(justify left bottom)
			)
		)
		(property "Sheetfile" "fpga-bank-16.kicad_sch"
			(at 146.05 197.4346 0)
			(effects
				(font
					(size 1.27 1.27)
				)
				(justify left top)
			)
		)
		(pin "HDMI{TMDS}" bidirectional
			(at 146.05 182.88 180)
			(effects
				(font
					(size 1.27 1.27)
				)
				(justify left)
			)
		)
		(pin "SD{SDIO}" bidirectional
			(at 146.05 180.34 180)
			(effects
				(font
					(size 1.27 1.27)
				)
				(justify left)
			)
		)
		(instances
			(project "sodimm-ddr5-tester"
				(path ""
					(page "16")
				)
			)
		)
	)
	(sheet
		(at 190.5 177.8)
		(size 38.1 19.05)
		(exclude_from_sim no)
		(in_bom yes)
		(on_board yes)
		(dnp no)
		(fields_autoplaced yes)
		(stroke
			(width 0.1524)
			(type solid)
		)
		(fill
			(color 0 0 0 0.0000)
		)
		(property "Sheetname" "FPGA banks unused"
			(at 190.5 177.0884 0)
			(effects
				(font
					(size 1.27 1.27)
				)
				(justify left bottom)
			)
		)
		(property "Sheetfile" "fpga-bank-13-15.kicad_sch"
			(at 190.5 197.4346 0)
			(effects
				(font
					(size 1.27 1.27)
				)
				(justify left top)
			)
		)
		(instances
			(project "sodimm-ddr5-tester"
				(path ""
					(page "14")
				)
			)
		)
	)
	(sheet
		(at 234.95 146.05)
		(size 38.1 50.8)
		(exclude_from_sim no)
		(in_bom yes)
		(on_board yes)
		(dnp no)
		(fields_autoplaced yes)
		(stroke
			(width 0.1524)
			(type solid)
		)
		(fill
			(color 0 0 0 0.0000)
		)
		(property "Sheetname" "FPGA MGT Interface"
			(at 234.95 145.3384 0)
			(effects
				(font
					(size 1.27 1.27)
				)
				(justify left bottom)
			)
		)
		(property "Sheetfile" "fpga-mgt.kicad_sch"
			(at 234.95 197.4346 0)
			(effects
				(font
					(size 1.27 1.27)
				)
				(justify left top)
			)
		)
		(pin "PCIE{PCIe_x4}" bidirectional
			(at 273.05 194.31 0)
			(effects
				(font
					(size 1.27 1.27)
				)
				(justify right)
			)
		)
		(instances
			(project "sodimm-ddr5-tester"
				(path ""
					(page "11")
				)
			)
		)
	)
	(sheet
		(at 146.05 209.55)
		(size 127 19.05)
		(exclude_from_sim no)
		(in_bom yes)
		(on_board yes)
		(dnp no)
		(fields_autoplaced yes)
		(stroke
			(width 0.1524)
			(type solid)
		)
		(fill
			(color 0 0 0 0.0000)
		)
		(property "Sheetname" "PCIe connector"
			(at 146.05 208.8384 0)
			(effects
				(font
					(size 1.27 1.27)
				)
				(justify left bottom)
			)
		)
		(property "Sheetfile" "pcie-connector.kicad_sch"
			(at 146.05 229.1846 0)
			(effects
				(font
					(size 1.27 1.27)
				)
				(justify left top)
			)
		)
		(pin "PCIE{PCIe_x4}" tri_state
			(at 273.05 212.09 0)
			(effects
				(font
					(size 1.27 1.27)
				)
				(justify right)
			)
		)
		(instances
			(project "sodimm-ddr5-tester"
				(path ""
					(page "12")
				)
			)
		)
	)
	(sheet_instances
		(path "/"
			(page "1")
		)
	)
)
